(kicad_pcb
	(version 20260206)
	(generator "pcbnew")
	(generator_version "10.0")
	(general
		(thickness 1.6)
		(legacy_teardrops no)
	)
	(paper "A4")
	(title_block
		(title "9054_F0T_PDB_BD_GPU_F_V04_1213_1550_OCP.brd")
		(comment 1 "Grand Teton / footprints 558-563 of 608")
	)
	(layers
		(0 "F.Cu" signal "TOP")
		(4 "In1.Cu" signal "GND")
		(6 "In2.Cu" signal "IN1")
		(8 "In3.Cu" signal "GND1")
		(10 "In4.Cu" signal "VCC")
		(12 "In5.Cu" signal "VCC1")
		(14 "In6.Cu" signal "GND2")
		(16 "In7.Cu" signal "IN2")
		(18 "In8.Cu" signal "GND3")
		(2 "B.Cu" signal "BOTTOM")
		(9 "F.Adhes" user "F.Adhesive")
		(11 "B.Adhes" user "B.Adhesive")
		(13 "F.Paste" user "Package Geometry/Pastemask Top")
		(15 "B.Paste" user "Package Geometry/Pastemask Bottom")
		(5 "F.SilkS" user "Ref Des/Silkscreen Top")
		(7 "B.SilkS" user "Ref Des/Silkscreen Bottom")
		(1 "F.Mask" user "Board Geometry/Soldermask Top")
		(3 "B.Mask" user "Board Geometry/Soldermask Bottom")
		(17 "Dwgs.User" user "User.Drawings")
		(19 "Cmts.User" user "User.Comments")
		(21 "Eco1.User" user "User.Eco1")
		(23 "Eco2.User" user "User.Eco2")
		(25 "Edge.Cuts" user "Board Geometry/Outline")
		(27 "Margin" user)
		(31 "F.CrtYd" user "Package Geometry/Place Bound Top")
		(29 "B.CrtYd" user "Package Geometry/Place Bound Bottom")
		(35 "F.Fab" user "Ref Des/Assembly Top")
		(33 "B.Fab" user "Ref Des/Assembly Bottom")
	)
	(footprint ""
		(layer "B.Cu")
		(at 278.4094 -68.961)
		(property "Reference" "R81"
			(at 0 0 0)
			(layer "B.SilkS")
			(hide yes)
			(effects
				(font
					(size 1.27 1.27)
				)
				(justify mirror)
			)
		)
		(property "Value" ""
			(at 0 0 0)
			(layer "B.Fab")
			(effects
				(font
					(size 1.27 1.27)
				)
				(justify mirror)
			)
		)
		(duplicate_pad_numbers_are_jumpers no)
		(fp_line
			(start -0.7874 -0.4064)
			(end -0.7874 0.4064)
			(stroke
				(width 0.1524)
				(type default)
			)
			(layer "B.SilkS")
		)
		(fp_line
			(start -0.7874 0.4064)
			(end 0.7874 0.4064)
			(stroke
				(width 0.1524)
				(type default)
			)
			(layer "B.SilkS")
		)
		(fp_line
			(start 0.7874 -0.4064)
			(end -0.7874 -0.4064)
			(stroke
				(width 0.1524)
				(type default)
			)
			(layer "B.SilkS")
		)
		(fp_line
			(start 0.7874 0.4064)
			(end 0.7874 -0.4064)
			(stroke
				(width 0.1524)
				(type default)
			)
			(layer "B.SilkS")
		)
		(fp_line
			(start -0.67945 -0.3048)
			(end -0.67945 0.3048)
			(stroke
				(width 0.1)
				(type default)
			)
			(layer "B.Fab")
		)
		(fp_line
			(start -0.67945 0.3048)
			(end -0.120396 0.3048)
			(stroke
				(width 0.1)
				(type default)
			)
			(layer "B.Fab")
		)
		(fp_line
			(start -0.12065 -0.3048)
			(end -0.67945 -0.3048)
			(stroke
				(width 0.1)
				(type default)
			)
			(layer "B.Fab")
		)
		(fp_line
			(start -0.12065 -0.2794)
			(end -0.12065 -0.3048)
			(stroke
				(width 0.1)
				(type default)
			)
			(layer "B.Fab")
		)
		(fp_line
			(start -0.120396 0.2794)
			(end 0.12065 0.2794)
			(stroke
				(width 0.1)
				(type default)
			)
			(layer "B.Fab")
		)
		(fp_line
			(start -0.120396 0.3048)
			(end -0.120396 0.2794)
			(stroke
				(width 0.1)
				(type default)
			)
			(layer "B.Fab")
		)
		(fp_line
			(start 0.12065 -0.305054)
			(end 0.12065 -0.2794)
			(stroke
				(width 0.1)
				(type default)
			)
			(layer "B.Fab")
		)
		(fp_line
			(start 0.12065 -0.2794)
			(end -0.12065 -0.2794)
			(stroke
				(width 0.1)
				(type default)
			)
			(layer "B.Fab")
		)
		(fp_line
			(start 0.12065 0.2794)
			(end 0.12065 0.3048)
			(stroke
				(width 0.1)
				(type default)
			)
			(layer "B.Fab")
		)
		(fp_line
			(start 0.12065 0.3048)
			(end 0.67945 0.3048)
			(stroke
				(width 0.1)
				(type default)
			)
			(layer "B.Fab")
		)
		(fp_line
			(start 0.67945 -0.305054)
			(end 0.12065 -0.305054)
			(stroke
				(width 0.1)
				(type default)
			)
			(layer "B.Fab")
		)
		(fp_line
			(start 0.67945 0.3048)
			(end 0.67945 -0.305054)
			(stroke
				(width 0.1)
				(type default)
			)
			(layer "B.Fab")
		)
		(pad "1" smd circle
			(at 0.40005 0 180)
			(size 0 0)
			(layers "B.Cu" "B.Mask" "B.Paste")
			(net "SMB_P52V_PDB_SCL")
		)
		(pad "2" smd circle
			(at -0.40005 0 180)
			(size 0 0)
			(layers "B.Cu" "B.Mask" "B.Paste")
			(net "SMB_P52V_PDB_SCL_R1")
		)
	)
	(footprint ""
		(layer "B.Cu")
		(at 284.7594 -65.659)
		(property "Reference" "PC7"
			(at 0 0 0)
			(layer "B.SilkS")
			(hide yes)
			(effects
				(font
					(size 1.27 1.27)
				)
				(justify mirror)
			)
		)
		(property "Value" ""
			(at 0 0 0)
			(layer "B.Fab")
			(effects
				(font
					(size 1.27 1.27)
				)
				(justify mirror)
			)
		)
		(duplicate_pad_numbers_are_jumpers no)
		(fp_line
			(start -0.7874 -0.4064)
			(end -0.7874 0.4064)
			(stroke
				(width 0.1524)
				(type default)
			)
			(layer "B.SilkS")
		)
		(fp_line
			(start -0.7874 0.4064)
			(end 0.7874 0.4064)
			(stroke
				(width 0.1524)
				(type default)
			)
			(layer "B.SilkS")
		)
		(fp_line
			(start 0.7874 -0.4064)
			(end -0.7874 -0.4064)
			(stroke
				(width 0.1524)
				(type default)
			)
			(layer "B.SilkS")
		)
		(fp_line
			(start 0.7874 0.4064)
			(end 0.7874 -0.4064)
			(stroke
				(width 0.1524)
				(type default)
			)
			(layer "B.SilkS")
		)
		(fp_line
			(start -0.67945 -0.3048)
			(end -0.67945 0.3048)
			(stroke
				(width 0.1)
				(type default)
			)
			(layer "B.Fab")
		)
		(fp_line
			(start -0.67945 0.3048)
			(end -0.120396 0.3048)
			(stroke
				(width 0.1)
				(type default)
			)
			(layer "B.Fab")
		)
		(fp_line
			(start -0.12065 -0.3048)
			(end -0.67945 -0.3048)
			(stroke
				(width 0.1)
				(type default)
			)
			(layer "B.Fab")
		)
		(fp_line
			(start -0.12065 -0.2794)
			(end -0.12065 -0.3048)
			(stroke
				(width 0.1)
				(type default)
			)
			(layer "B.Fab")
		)
		(fp_line
			(start -0.120396 0.2794)
			(end 0.12065 0.2794)
			(stroke
				(width 0.1)
				(type default)
			)
			(layer "B.Fab")
		)
		(fp_line
			(start -0.120396 0.3048)
			(end -0.120396 0.2794)
			(stroke
				(width 0.1)
				(type default)
			)
			(layer "B.Fab")
		)
		(fp_line
			(start 0.12065 -0.305054)
			(end 0.12065 -0.2794)
			(stroke
				(width 0.1)
				(type default)
			)
			(layer "B.Fab")
		)
		(fp_line
			(start 0.12065 -0.2794)
			(end -0.12065 -0.2794)
			(stroke
				(width 0.1)
				(type default)
			)
			(layer "B.Fab")
		)
		(fp_line
			(start 0.12065 0.2794)
			(end 0.12065 0.3048)
			(stroke
				(width 0.1)
				(type default)
			)
			(layer "B.Fab")
		)
		(fp_line
			(start 0.12065 0.3048)
			(end 0.67945 0.3048)
			(stroke
				(width 0.1)
				(type default)
			)
			(layer "B.Fab")
		)
		(fp_line
			(start 0.67945 -0.305054)
			(end 0.12065 -0.305054)
			(stroke
				(width 0.1)
				(type default)
			)
			(layer "B.Fab")
		)
		(fp_line
			(start 0.67945 0.3048)
			(end 0.67945 -0.305054)
			(stroke
				(width 0.1)
				(type default)
			)
			(layer "B.Fab")
		)
		(pad "1" smd circle
			(at 0.40005 0 180)
			(size 0 0)
			(layers "B.Cu" "B.Mask" "B.Paste")
			(net "P52V_HS1_TMR")
		)
		(pad "2" smd circle
			(at -0.40005 0 180)
			(size 0 0)
			(layers "B.Cu" "B.Mask" "B.Paste")
			(net "GND_FIELD_SIGNAL")
		)
	)
	(footprint ""
		(layer "B.Cu")
		(at 169.718736 -69.596)
		(property "Reference" "PC611"
			(at 0 0 0)
			(layer "B.SilkS")
			(hide yes)
			(effects
				(font
					(size 1.27 1.27)
				)
				(justify mirror)
			)
		)
		(property "Value" ""
			(at 0 0 0)
			(layer "B.Fab")
			(effects
				(font
					(size 1.27 1.27)
				)
				(justify mirror)
			)
		)
		(duplicate_pad_numbers_are_jumpers no)
		(fp_line
			(start -1.2954 -0.5842)
			(end -1.2954 0.5842)
			(stroke
				(width 0.1524)
				(type default)
			)
			(layer "B.SilkS")
		)
		(fp_line
			(start -1.2954 0.5842)
			(end 1.2954 0.5842)
			(stroke
				(width 0.1524)
				(type default)
			)
			(layer "B.SilkS")
		)
		(fp_line
			(start 1.2954 -0.5842)
			(end -1.2954 -0.5842)
			(stroke
				(width 0.1524)
				(type default)
			)
			(layer "B.SilkS")
		)
		(fp_line
			(start 1.2954 0.5842)
			(end 1.2954 -0.5842)
			(stroke
				(width 0.1524)
				(type default)
			)
			(layer "B.SilkS")
		)
		(fp_line
			(start -1.1938 -0.4064)
			(end -1.1938 0.4064)
			(stroke
				(width 0.1)
				(type default)
			)
			(layer "B.Fab")
		)
		(fp_line
			(start -1.1938 0.4064)
			(end -0.8636 0.4064)
			(stroke
				(width 0.1)
				(type default)
			)
			(layer "B.Fab")
		)
		(fp_line
			(start -0.8636 -0.4572)
			(end -0.8636 -0.4064)
			(stroke
				(width 0.1)
				(type default)
			)
			(layer "B.Fab")
		)
		(fp_line
			(start -0.8636 -0.4064)
			(end -1.1938 -0.4064)
			(stroke
				(width 0.1)
				(type default)
			)
			(layer "B.Fab")
		)
		(fp_line
			(start -0.8636 0.4064)
			(end -0.8636 0.4572)
			(stroke
				(width 0.1)
				(type default)
			)
			(layer "B.Fab")
		)
		(fp_line
			(start -0.8636 0.4572)
			(end 0.8636 0.4572)
			(stroke
				(width 0.1)
				(type default)
			)
			(layer "B.Fab")
		)
		(fp_line
			(start 0.8636 -0.4572)
			(end -0.8636 -0.4572)
			(stroke
				(width 0.1)
				(type default)
			)
			(layer "B.Fab")
		)
		(fp_line
			(start 0.8636 -0.4064)
			(end 0.8636 -0.4572)
			(stroke
				(width 0.1)
				(type default)
			)
			(layer "B.Fab")
		)
		(fp_line
			(start 0.8636 0.4064)
			(end 1.1938 0.4064)
			(stroke
				(width 0.1)
				(type default)
			)
			(layer "B.Fab")
		)
		(fp_line
			(start 0.8636 0.4572)
			(end 0.8636 0.4064)
			(stroke
				(width 0.1)
				(type default)
			)
			(layer "B.Fab")
		)
		(fp_line
			(start 1.1938 -0.4064)
			(end 0.8636 -0.4064)
			(stroke
				(width 0.1)
				(type default)
			)
			(layer "B.Fab")
		)
		(fp_line
			(start 1.1938 0.4064)
			(end 1.1938 -0.4064)
			(stroke
				(width 0.1)
				(type default)
			)
			(layer "B.Fab")
		)
		(pad "1" smd rect
			(at 0.7366 0 270)
			(size 0.7112 0.8128)
			(layers "B.Cu" "B.Mask" "B.Paste")
			(net "P52V_HS2_VCAP")
		)
		(pad "2" smd rect
			(at -0.7366 0 270)
			(size 0.7112 0.8128)
			(layers "B.Cu" "B.Mask" "B.Paste")
			(net "GND1_FIELD_SIGNAL")
		)
	)
	(footprint ""
		(layer "B.Cu")
		(at 168.829736 -64.643)
		(property "Reference" "PR7030"
			(at 0 0 0)
			(layer "B.SilkS")
			(hide yes)
			(effects
				(font
					(size 1.27 1.27)
				)
				(justify mirror)
			)
		)
		(property "Value" ""
			(at 0 0 0)
			(layer "B.Fab")
			(effects
				(font
					(size 1.27 1.27)
				)
				(justify mirror)
			)
		)
		(duplicate_pad_numbers_are_jumpers no)
		(fp_line
			(start -0.7874 -0.4064)
			(end -0.7874 0.4064)
			(stroke
				(width 0.1524)
				(type default)
			)
			(layer "B.SilkS")
		)
		(fp_line
			(start -0.7874 0.4064)
			(end 0.7874 0.4064)
			(stroke
				(width 0.1524)
				(type default)
			)
			(layer "B.SilkS")
		)
		(fp_line
			(start 0.7874 -0.4064)
			(end -0.7874 -0.4064)
			(stroke
				(width 0.1524)
				(type default)
			)
			(layer "B.SilkS")
		)
		(fp_line
			(start 0.7874 0.4064)
			(end 0.7874 -0.4064)
			(stroke
				(width 0.1524)
				(type default)
			)
			(layer "B.SilkS")
		)
		(fp_line
			(start -0.67945 -0.3048)
			(end -0.67945 0.3048)
			(stroke
				(width 0.1)
				(type default)
			)
			(layer "B.Fab")
		)
		(fp_line
			(start -0.67945 0.3048)
			(end -0.120396 0.3048)
			(stroke
				(width 0.1)
				(type default)
			)
			(layer "B.Fab")
		)
		(fp_line
			(start -0.12065 -0.3048)
			(end -0.67945 -0.3048)
			(stroke
				(width 0.1)
				(type default)
			)
			(layer "B.Fab")
		)
		(fp_line
			(start -0.12065 -0.2794)
			(end -0.12065 -0.3048)
			(stroke
				(width 0.1)
				(type default)
			)
			(layer "B.Fab")
		)
		(fp_line
			(start -0.120396 0.2794)
			(end 0.12065 0.2794)
			(stroke
				(width 0.1)
				(type default)
			)
			(layer "B.Fab")
		)
		(fp_line
			(start -0.120396 0.3048)
			(end -0.120396 0.2794)
			(stroke
				(width 0.1)
				(type default)
			)
			(layer "B.Fab")
		)
		(fp_line
			(start 0.12065 -0.305054)
			(end 0.12065 -0.2794)
			(stroke
				(width 0.1)
				(type default)
			)
			(layer "B.Fab")
		)
		(fp_line
			(start 0.12065 -0.2794)
			(end -0.12065 -0.2794)
			(stroke
				(width 0.1)
				(type default)
			)
			(layer "B.Fab")
		)
		(fp_line
			(start 0.12065 0.2794)
			(end 0.12065 0.3048)
			(stroke
				(width 0.1)
				(type default)
			)
			(layer "B.Fab")
		)
		(fp_line
			(start 0.12065 0.3048)
			(end 0.67945 0.3048)
			(stroke
				(width 0.1)
				(type default)
			)
			(layer "B.Fab")
		)
		(fp_line
			(start 0.67945 -0.305054)
			(end 0.12065 -0.305054)
			(stroke
				(width 0.1)
				(type default)
			)
			(layer "B.Fab")
		)
		(fp_line
			(start 0.67945 0.3048)
			(end 0.67945 -0.305054)
			(stroke
				(width 0.1)
				(type default)
			)
			(layer "B.Fab")
		)
		(pad "1" smd circle
			(at 0.40005 0 180)
			(size 0 0)
			(layers "B.Cu" "B.Mask" "B.Paste")
			(net "P52V_HS2_ISET")
		)
		(pad "2" smd circle
			(at -0.40005 0 180)
			(size 0 0)
			(layers "B.Cu" "B.Mask" "B.Paste")
			(net "GND1_FIELD_SIGNAL")
		)
	)
	(footprint ""
		(layer "B.Cu")
		(at 172.7454 -63.754 90)
		(property "Reference" "PR6979"
			(at 0 0 90)
			(layer "B.SilkS")
			(hide yes)
			(effects
				(font
					(size 1.27 1.27)
				)
				(justify mirror)
			)
		)
		(property "Value" ""
			(at 0 0 90)
			(layer "B.Fab")
			(effects
				(font
					(size 1.27 1.27)
				)
				(justify mirror)
			)
		)
		(duplicate_pad_numbers_are_jumpers no)
		(fp_line
			(start 0.7874 -0.4064)
			(end -0.7874 -0.4064)
			(stroke
				(width 0.1524)
				(type default)
			)
			(layer "B.SilkS")
		)
		(fp_line
			(start -0.7874 -0.4064)
			(end -0.7874 0.4064)
			(stroke
				(width 0.1524)
				(type default)
			)
			(layer "B.SilkS")
		)
		(fp_line
			(start 0.7874 0.4064)
			(end 0.7874 -0.4064)
			(stroke
				(width 0.1524)
				(type default)
			)
			(layer "B.SilkS")
		)
		(fp_line
			(start -0.7874 0.4064)
			(end 0.7874 0.4064)
			(stroke
				(width 0.1524)
				(type default)
			)
			(layer "B.SilkS")
		)
		(fp_line
			(start 0.67945 -0.305054)
			(end 0.12065 -0.305054)
			(stroke
				(width 0.1)
				(type default)
			)
			(layer "B.Fab")
		)
		(fp_line
			(start 0.12065 -0.305054)
			(end 0.12065 -0.2794)
			(stroke
				(width 0.1)
				(type default)
			)
			(layer "B.Fab")
		)
		(fp_line
			(start -0.12065 -0.3048)
			(end -0.67945 -0.3048)
			(stroke
				(width 0.1)
				(type default)
			)
			(layer "B.Fab")
		)
		(fp_line
			(start -0.67945 -0.3048)
			(end -0.67945 0.3048)
			(stroke
				(width 0.1)
				(type default)
			)
			(layer "B.Fab")
		)
		(fp_line
			(start 0.12065 -0.2794)
			(end -0.12065 -0.2794)
			(stroke
				(width 0.1)
				(type default)
			)
			(layer "B.Fab")
		)
		(fp_line
			(start -0.12065 -0.2794)
			(end -0.12065 -0.3048)
			(stroke
				(width 0.1)
				(type default)
			)
			(layer "B.Fab")
		)
		(fp_line
			(start 0.12065 0.2794)
			(end 0.12065 0.3048)
			(stroke
				(width 0.1)
				(type default)
			)
			(layer "B.Fab")
		)
		(fp_line
			(start -0.120396 0.2794)
			(end 0.12065 0.2794)
			(stroke
				(width 0.1)
				(type default)
			)
			(layer "B.Fab")
		)
		(fp_line
			(start 0.67945 0.3048)
			(end 0.67945 -0.305054)
			(stroke
				(width 0.1)
				(type default)
			)
			(layer "B.Fab")
		)
		(fp_line
			(start 0.12065 0.3048)
			(end 0.67945 0.3048)
			(stroke
				(width 0.1)
				(type default)
			)
			(layer "B.Fab")
		)
		(fp_line
			(start -0.120396 0.3048)
			(end -0.120396 0.2794)
			(stroke
				(width 0.1)
				(type default)
			)
			(layer "B.Fab")
		)
		(fp_line
			(start -0.67945 0.3048)
			(end -0.120396 0.3048)
			(stroke
				(width 0.1)
				(type default)
			)
			(layer "B.Fab")
		)
		(pad "1" smd circle
			(at 0.40005 0 270)
			(size 0 0)
			(layers "B.Cu" "B.Mask" "B.Paste")
			(net "P52V_HS2_OV")
		)
		(pad "2" smd circle
			(at -0.40005 0 270)
			(size 0 0)
			(layers "B.Cu" "B.Mask" "B.Paste")
			(net "GND1_FIELD_SIGNAL")
		)
	)
	(footprint ""
		(layer "B.Cu")
		(at 104.013 -54.356)
		(property "Reference" "PC596"
			(at 0 0 0)
			(layer "B.SilkS")
			(hide yes)
			(effects
				(font
					(size 1.27 1.27)
				)
				(justify mirror)
			)
		)
		(property "Value" ""
			(at 0 0 0)
			(layer "B.Fab")
			(effects
				(font
					(size 1.27 1.27)
				)
				(justify mirror)
			)
		)
		(duplicate_pad_numbers_are_jumpers no)
		(fp_line
			(start -1.2954 -0.5842)
			(end -1.2954 0.5842)
			(stroke
				(width 0.1524)
				(type default)
			)
			(layer "B.SilkS")
		)
		(fp_line
			(start -1.2954 0.5842)
			(end 1.2954 0.5842)
			(stroke
				(width 0.1524)
				(type default)
			)
			(layer "B.SilkS")
		)
		(fp_line
			(start 1.2954 -0.5842)
			(end -1.2954 -0.5842)
			(stroke
				(width 0.1524)
				(type default)
			)
			(layer "B.SilkS")
		)
		(fp_line
			(start 1.2954 0.5842)
			(end 1.2954 -0.5842)
			(stroke
				(width 0.1524)
				(type default)
			)
			(layer "B.SilkS")
		)
		(fp_line
			(start -1.1938 -0.4064)
			(end -1.1938 0.4064)
			(stroke
				(width 0.1)
				(type default)
			)
			(layer "B.Fab")
		)
		(fp_line
			(start -1.1938 0.4064)
			(end -0.8636 0.4064)
			(stroke
				(width 0.1)
				(type default)
			)
			(layer "B.Fab")
		)
		(fp_line
			(start -0.8636 -0.4572)
			(end -0.8636 -0.4064)
			(stroke
				(width 0.1)
				(type default)
			)
			(layer "B.Fab")
		)
		(fp_line
			(start -0.8636 -0.4064)
			(end -1.1938 -0.4064)
			(stroke
				(width 0.1)
				(type default)
			)
			(layer "B.Fab")
		)
		(fp_line
			(start -0.8636 0.4064)
			(end -0.8636 0.4572)
			(stroke
				(width 0.1)
				(type default)
			)
			(layer "B.Fab")
		)
		(fp_line
			(start -0.8636 0.4572)
			(end 0.8636 0.4572)
			(stroke
				(width 0.1)
				(type default)
			)
			(layer "B.Fab")
		)
		(fp_line
			(start 0.8636 -0.4572)
			(end -0.8636 -0.4572)
			(stroke
				(width 0.1)
				(type default)
			)
			(layer "B.Fab")
		)
		(fp_line
			(start 0.8636 -0.4064)
			(end 0.8636 -0.4572)
			(stroke
				(width 0.1)
				(type default)
			)
			(layer "B.Fab")
		)
		(fp_line
			(start 0.8636 0.4064)
			(end 1.1938 0.4064)
			(stroke
				(width 0.1)
				(type default)
			)
			(layer "B.Fab")
		)
		(fp_line
			(start 0.8636 0.4572)
			(end 0.8636 0.4064)
			(stroke
				(width 0.1)
				(type default)
			)
			(layer "B.Fab")
		)
		(fp_line
			(start 1.1938 -0.4064)
			(end 0.8636 -0.4064)
			(stroke
				(width 0.1)
				(type default)
			)
			(layer "B.Fab")
		)
		(fp_line
			(start 1.1938 0.4064)
			(end 1.1938 -0.4064)
			(stroke
				(width 0.1)
				(type default)
			)
			(layer "B.Fab")
		)
		(pad "1" smd rect
			(at 0.7366 0 270)
			(size 0.7112 0.8128)
			(layers "B.Cu" "B.Mask" "B.Paste")
			(net "P52V_HS2_GATE_RC")
		)
		(pad "2" smd rect
			(at -0.7366 0 270)
			(size 0.7112 0.8128)
			(layers "B.Cu" "B.Mask" "B.Paste")
			(net "P52V_HS2")
		)
	)
)
